G04 ================== begin FILE IDENTIFICATION RECORD ==================*
G04 Layout Name:  t6m_pdb_d_0928_1400_274.brd*
G04 Film Name:    outline*
G04 File Format:  Gerber RS274X*
G04 File Origin:  Cadence Allegro 16.3-S048*
G04 Origin Date:  Tue Nov 26 11:01:52 2013*
G04 *
G04 Layer:  BOARD GEOMETRY/OUTLINE*
G04 *
G04 Offset:    (0.00 0.00)*
G04 Mirror:    No*
G04 Mode:      Positive*
G04 Rotation:  0*
G04 FullContactRelief:  No*
G04 UndefLineWidth:     6.00*
G04 ================== end FILE IDENTIFICATION RECORD ====================*
%FSLAX25Y25*MOIN*%
%IR0*IPPOS*OFA0.00000B0.00000*MIA0B0*SFA1.00000B1.00000*%
%ADD10C,.006*%
G75*
%LPD*%
G75*
G54D10*
G01X104331Y0D02*
X397638D01*
G03X405512Y7874I0J7874D01*
G01Y2078740D01*
G03X397638Y2086614I-7874J0D01*
G01X104331D01*
G03X98425Y2080709I0J-5906D01*
G01Y2076772D01*
G02X92520Y2070866I-5905J-1D01*
G01X5906D01*
G03X0Y2064961I-1J-5905D01*
G01Y21654D01*
G03X5906Y15748I5906J0D01*
G01X92520D01*
G02X98425Y9843I0J-5905D01*
G01Y5906D01*
G03X104331Y0I5906J0D01*
G01X317323Y1885039D02*
Y1881102D01*
G02X296850I-10237J0D01*
G01Y1885039D01*
G02X317323I10236J0D01*
M02*
